(kicad_pcb
	(version 20221018)
	(generator pcbnew)
	(general
    (thickness 1.518)
  )
	(paper "A4")
	(title_block
    (title "Kria K26 Devboard")
    (date "2024-03-26")
    (rev "1.2.5")
    (comment 1 "www.antmicro.com")
    (comment 2 "Antmicro Ltd.")
		(comment 9 "footprints 508-514 of 660")
	)
	(layers
    (0 "F.Cu" mixed)
    (1 "In1.Cu" power)
    (2 "In2.Cu" mixed)
    (3 "In3.Cu" power)
    (4 "In4.Cu" mixed)
    (5 "In5.Cu" power)
    (6 "In6.Cu" mixed)
    (31 "B.Cu" power)
    (32 "B.Adhes" user "B.Adhesive")
    (33 "F.Adhes" user "F.Adhesive")
    (34 "B.Paste" user)
    (35 "F.Paste" user)
    (36 "B.SilkS" user "B.Silkscreen")
    (37 "F.SilkS" user "F.Silkscreen")
    (38 "B.Mask" user)
    (39 "F.Mask" user)
    (40 "Dwgs.User" user "User.Drawings")
    (41 "Cmts.User" user "User.Comments")
    (42 "Eco1.User" user "User.Eco1")
    (43 "Eco2.User" user "User.Eco2")
    (44 "Edge.Cuts" user)
    (45 "Margin" user)
    (46 "B.CrtYd" user "B.Courtyard")
    (47 "F.CrtYd" user "F.Courtyard")
    (48 "B.Fab" user)
    (49 "F.Fab" user)
  )
	(footprint "kria-k26-devboard-footprints:C_0603_1608Metric" (layer "B.Cu")
    (at 134.3 90.950002 -90)
    (descr "Capacitor SMD 0603")
    (tags "capacitor 0603")
    (property "Author" "Antmicro")
    (property "Dielectric" "")
    (property "License" "Apache-2.0")
    (property "MPN" "C1608X5R1E106M080AC")
    (property "Manufacturer" "TDK")
    (property "Sheetfile" "dc-dc-conventers.kicad_sch")
    (property "Sheetname" "DC/DC conventers")
    (property "Val" "10u/25V")
    (property "Voltage" "")
    (property "ki_description" " ")
    (attr smd)
    (fp_text reference "C205" (at -1.520002 0.84 90) (layer "B.SilkS")
        (effects (font (size 0.7 0.7) (thickness 0.15)) (justify left bottom mirror))
    )
    (fp_text value "C_10u_25V_0603" (at 0 -1.6 90) (layer "B.Fab") hide
        (effects (font (size 0.7 0.7) (thickness 0.15)) (justify left bottom mirror))
    )
    (fp_text user "Author: Antmicro" (at -1.682 -4.894 90) (layer "B.Fab") hide
        (effects (font (size 0.7 0.7) (thickness 0.15)) (justify left bottom mirror))
    )
    (fp_text user "${REFERENCE}" (at -1.682 -3.895 90) (layer "B.Fab") hide
        (effects (font (size 0.7 0.7) (thickness 0.15)) (justify left bottom mirror))
    )
    (fp_text user "License: Apache-2.0" (at -1.682 -5.895 90) (layer "B.Fab") hide
        (effects (font (size 0.7 0.7) (thickness 0.15)) (justify left bottom mirror))
    )
    (fp_line (start -0.3 -0.3) (end 0.3 -0.3)
      (stroke (width 0.15) (type solid)) (layer "B.SilkS"))
    (fp_line (start -0.3 0.3) (end 0.3 0.3)
      (stroke (width 0.15) (type solid)) (layer "B.SilkS"))
    (fp_rect (start -1.24 0.7) (end 1.24 -0.7)
      (stroke (width 0.05) (type solid)) (fill none) (layer "B.CrtYd"))
    (fp_rect (start -0.8 0.4) (end 0.8 -0.4)
      (stroke (width 0.15) (type solid)) (fill none) (layer "B.Fab"))
    (pad "1" smd roundrect (at -0.7 0 270) (size 0.6 0.8) (layers "B.Cu" "B.Paste" "B.Mask") (roundrect_rratio 0.2)
      (net 14 "/Power Supply/DC/DC conventers/DC_MAIN_BUS") (pintype "passive"))
    (pad "2" smd roundrect (at 0.7 0 270) (size 0.6 0.8) (layers "B.Cu" "B.Paste" "B.Mask") (roundrect_rratio 0.2)
      (net 1 "GND") (pintype "passive"))
  )
	(footprint "kria-k26-devboard-footprints:C_0402_1005Metric" (layer "B.Cu")
    (at 95.49 86.85 -90)
    (descr "Capacitor SMD 0402")
    (tags "capacitor SMD 0402")
    (property "Author" "Antmicro")
    (property "Dielectric" "X5R")
    (property "License" "Apache-2.0")
    (property "MPN" "GRM155R61H104KE14D")
    (property "Manufacturer" "Murata")
    (property "Sheetfile" "dp.kicad_sch")
    (property "Sheetname" "Display Port")
    (property "Val" "100n")
    (property "Voltage" "50V")
    (property "ki_description" " ")
    (attr smd)
    (fp_text reference "C3" (at -0.69 -1.37 90) (layer "B.SilkS")
        (effects (font (size 0.7 0.7) (thickness 0.15)) (justify left bottom mirror))
    )
    (fp_text value "C_100n_0402" (at 0 -1.4 90) (layer "B.Fab") hide
        (effects (font (size 0.7 0.7) (thickness 0.15)) (justify left bottom mirror))
    )
    (fp_text user "${REFERENCE}" (at -0.932 -3.168 90) (layer "B.Fab") hide
        (effects (font (size 0.7 0.7) (thickness 0.15)) (justify left bottom mirror))
    )
    (fp_text user "Author: Antmicro" (at -0.932 -4.17 90) (layer "B.Fab") hide
        (effects (font (size 0.7 0.7) (thickness 0.15)) (justify left bottom mirror))
    )
    (fp_text user "License: Apache-2.0" (at -0.932 -5.17 90) (layer "B.Fab") hide
        (effects (font (size 0.7 0.7) (thickness 0.15)) (justify left bottom mirror))
    )
    (fp_rect (start -0.94 0.47) (end 0.94 -0.47)
      (stroke (width 0.05) (type solid)) (fill none) (layer "B.CrtYd"))
    (fp_rect (start -0.499 0.249) (end 0.499 -0.249)
      (stroke (width 0.15) (type solid)) (fill none) (layer "B.Fab"))
    (pad "1" smd roundrect (at -0.484 0 270) (size 0.59 0.64) (layers "B.Cu" "B.Paste" "B.Mask") (roundrect_rratio 0.25)
      (net 17 "PS_1V8") (pintype "passive"))
    (pad "2" smd roundrect (at 0.484 0 270) (size 0.59 0.64) (layers "B.Cu" "B.Paste" "B.Mask") (roundrect_rratio 0.25)
      (net 1 "GND") (pintype "passive"))
  )
	(footprint "kria-k26-devboard-footprints:TSSOP-14_4.4x5mm_P0.65mm" (layer "B.Cu")
    (at 92.6 79.7 90)
    (descr "TSSOP, 14 Pin (JEDEC MO-153 Var AB-1 https://www.jedec.org/document_search?search_api_views_fulltext=MO-153), generated with kicad-footprint-generator ipc_gullwing_generator.py")
    (tags "TSSOP SO")
    (property "Author" "Antmicro")
    (property "License" "Apache-2.0")
    (property "MPN" "FIN1019MTCX")
    (property "Manufacturer" "ON Semiconductor")
    (property "Sheetfile" "dp.kicad_sch")
    (property "Sheetname" "Display Port")
    (property "ki_description" "3.3V LVDS High Speed Differential Driver/Receiver, 400Mbps, TSSOP-14")
    (property "ki_keywords" "lvds driver reciever")
    (attr smd)
    (fp_text reference "U2" (at 0.5 3.18 270) (layer "B.SilkS")
        (effects (font (size 0.7 0.7) (thickness 0.15)) (justify left mirror))
    )
    (fp_text value "FIN1019MTC" (at -3.8 -4.3 270) (layer "B.Fab") hide
        (effects (font (size 0.7 0.7) (thickness 0.15)) (justify left bottom mirror))
    )
    (fp_text user "." (at -3.7 2.8 270) (layer "B.SilkS")
        (effects (font (size 1 1) (thickness 0.15)) (justify left mirror))
    )
    (fp_text user "Author: Antmicro" (at -3.851 -6.45 270) (layer "B.Fab") hide
        (effects (font (size 0.7 0.7) (thickness 0.15)) (justify left bottom mirror))
    )
    (fp_text user "License: Apache-2.0" (at -3.851 -7.45 270) (layer "B.Fab") hide
        (effects (font (size 0.7 0.7) (thickness 0.15)) (justify left bottom mirror))
    )
    (fp_text user "${REFERENCE}" (at -3.851 -5.45 270) (layer "B.Fab") hide
        (effects (font (size 0.7 0.7) (thickness 0.15)) (justify left bottom mirror))
    )
    (fp_line (start -2.9 2.3) (end -2.3 2.3)
      (stroke (width 0.15) (type solid)) (layer "B.SilkS"))
    (fp_line (start -2.3 -2.6) (end -2.3 -2.3)
      (stroke (width 0.15) (type solid)) (layer "B.SilkS"))
    (fp_line (start -2.3 2.61) (end -2.3 2.3)
      (stroke (width 0.15) (type solid)) (layer "B.SilkS"))
    (fp_line (start -2.3 2.61) (end 2.3 2.605)
      (stroke (width 0.15) (type solid)) (layer "B.SilkS"))
    (fp_line (start 2.3 -2.6) (end -2.3 -2.6)
      (stroke (width 0.15) (type solid)) (layer "B.SilkS"))
    (fp_line (start 2.3 -2.3) (end 2.3 -2.6)
      (stroke (width 0.15) (type solid)) (layer "B.SilkS"))
    (fp_line (start 2.3 2.3) (end 2.3 2.605)
      (stroke (width 0.15) (type solid)) (layer "B.SilkS"))
    (fp_line (start -3.7 -2.6) (end 3.7 -2.6)
      (stroke (width 0.05) (type solid)) (layer "B.CrtYd"))
    (fp_line (start -3.7 2.6) (end -3.7 -2.6)
      (stroke (width 0.05) (type solid)) (layer "B.CrtYd"))
    (fp_line (start 3.7 -2.6) (end 3.7 2.6)
      (stroke (width 0.05) (type solid)) (layer "B.CrtYd"))
    (fp_line (start 3.7 2.6) (end -3.7 2.6)
      (stroke (width 0.05) (type solid)) (layer "B.CrtYd"))
    (fp_line (start -2.202 -2.499) (end -2.202 1.5)
      (stroke (width 0.15) (type solid)) (layer "B.Fab"))
    (fp_line (start -2.202 1.5) (end -1.2 2.5)
      (stroke (width 0.15) (type solid)) (layer "B.Fab"))
    (fp_line (start -1.2 2.5) (end 2.2 2.5)
      (stroke (width 0.15) (type solid)) (layer "B.Fab"))
    (fp_line (start 2.2 -2.499) (end -2.202 -2.499)
      (stroke (width 0.15) (type solid)) (layer "B.Fab"))
    (fp_line (start 2.2 2.5) (end 2.2 -2.499)
      (stroke (width 0.15) (type solid)) (layer "B.Fab"))
    (pad "1" smd roundrect (at -2.863 1.95 90) (size 1.475 0.4) (layers "B.Cu" "B.Paste" "B.Mask") (roundrect_rratio 0.25)
      (net 125 "/Display Port/DP_OE") (pinfunction "DE") (pintype "input"))
    (pad "2" smd roundrect (at -2.863 1.301 90) (size 1.475 0.4) (layers "B.Cu" "B.Paste" "B.Mask") (roundrect_rratio 0.25)
      (net 124 "/Display Port/DP_AUX_OUT") (pinfunction "DI") (pintype "input"))
    (pad "3" smd roundrect (at -2.863 0.652 90) (size 1.475 0.4) (layers "B.Cu" "B.Paste" "B.Mask") (roundrect_rratio 0.25)
      (net 701 "unconnected-(U2-NC-Pad3)") (pinfunction "NC") (pintype "no_connect"))
    (pad "4" smd roundrect (at -2.863 0 90) (size 1.475 0.4) (layers "B.Cu" "B.Paste" "B.Mask") (roundrect_rratio 0.25)
      (net 126 "/Display Port/DP_AUX_IN") (pinfunction "RO") (pintype "output"))
    (pad "5" smd roundrect (at -2.863 -0.65 90) (size 1.475 0.4) (layers "B.Cu" "B.Paste" "B.Mask") (roundrect_rratio 0.25)
      (net 702 "unconnected-(U2-NC-Pad5)") (pinfunction "NC") (pintype "no_connect"))
    (pad "6" smd roundrect (at -2.863 -1.3 90) (size 1.475 0.4) (layers "B.Cu" "B.Paste" "B.Mask") (roundrect_rratio 0.25)
      (net 703 "unconnected-(U2-NC-Pad6)") (pinfunction "NC") (pintype "no_connect"))
    (pad "7" smd roundrect (at -2.863 -1.949 90) (size 1.475 0.4) (layers "B.Cu" "B.Paste" "B.Mask") (roundrect_rratio 0.25)
      (net 1 "GND") (pinfunction "GND") (pintype "power_in"))
    (pad "8" smd roundrect (at 2.862 -1.949 90) (size 1.475 0.4) (layers "B.Cu" "B.Paste" "B.Mask") (roundrect_rratio 0.25)
      (net 125 "/Display Port/DP_OE") (pinfunction "~{RE}") (pintype "input"))
    (pad "9" smd roundrect (at 2.862 -1.3 90) (size 1.475 0.4) (layers "B.Cu" "B.Paste" "B.Mask") (roundrect_rratio 0.25)
      (net 98 "/Display Port/DP_AUX_N") (pinfunction "RI-") (pintype "input"))
    (pad "10" smd roundrect (at 2.862 -0.65 90) (size 1.475 0.4) (layers "B.Cu" "B.Paste" "B.Mask") (roundrect_rratio 0.25)
      (net 96 "/Display Port/DP_AUX_P") (pinfunction "RI+") (pintype "input"))
    (pad "11" smd roundrect (at 2.862 0 90) (size 1.475 0.4) (layers "B.Cu" "B.Paste" "B.Mask") (roundrect_rratio 0.25)
      (net 98 "/Display Port/DP_AUX_N") (pinfunction "DO-") (pintype "output"))
    (pad "12" smd roundrect (at 2.862 0.652 90) (size 1.475 0.4) (layers "B.Cu" "B.Paste" "B.Mask") (roundrect_rratio 0.25)
      (net 96 "/Display Port/DP_AUX_P") (pinfunction "DO+") (pintype "output"))
    (pad "13" smd roundrect (at 2.862 1.301 90) (size 1.475 0.4) (layers "B.Cu" "B.Paste" "B.Mask") (roundrect_rratio 0.25)
      (net 704 "unconnected-(U2-NC-Pad13)") (pinfunction "NC") (pintype "no_connect"))
    (pad "14" smd roundrect (at 2.862 1.95 90) (size 1.475 0.4) (layers "B.Cu" "B.Paste" "B.Mask") (roundrect_rratio 0.25)
      (net 15 "PS_3V3") (pinfunction "VCC") (pintype "power_in"))
  )
	(footprint "kria-k26-devboard-footprints:R_0402_1005Metric" (layer "B.Cu")
    (at 117.9 92.7 90)
    (descr "Resistor SMD 0402")
    (tags "resistor SMD 0402")
    (property "Author" "Antmicro")
    (property "License" "Apache-2.0")
    (property "MPN" "CR0402-FX-1202GLF")
    (property "Manufacturer" "Bourns")
    (property "Sheetfile" "usb.kicad_sch")
    (property "Sheetname" "USB")
    (property "Tolerance" "1%")
    (property "Val" "12k")
    (property "ki_description" "12k resistor in 0402 package with 1% tolerance")
    (attr smd)
    (fp_text reference "R38" (at -0.84 0.33 270) (layer "B.SilkS")
        (effects (font (size 0.7 0.7) (thickness 0.15)) (justify left bottom mirror))
    )
    (fp_text value "R_12k_0402" (at 0 -1.4 270) (layer "B.Fab") hide
        (effects (font (size 0.7 0.7) (thickness 0.15)) (justify left bottom mirror))
    )
    (fp_text user "Author: Antmicro" (at -0.95 -4.169 270) (layer "B.Fab") hide
        (effects (font (size 0.7 0.7) (thickness 0.15)) (justify left bottom mirror))
    )
    (fp_text user "License: Apache-2.0" (at -0.95 -5.169 270) (layer "B.Fab") hide
        (effects (font (size 0.7 0.7) (thickness 0.15)) (justify left bottom mirror))
    )
    (fp_text user "${REFERENCE}" (at -0.95 -3.168 270) (layer "B.Fab") hide
        (effects (font (size 0.7 0.7) (thickness 0.15)) (justify left bottom mirror))
    )
    (fp_rect (start -0.93 0.47) (end 0.93 -0.47)
      (stroke (width 0.05) (type solid)) (fill none) (layer "B.CrtYd"))
    (fp_rect (start -0.5 0.25) (end 0.5 -0.25)
      (stroke (width 0.15) (type solid)) (fill none) (layer "B.Fab"))
    (pad "1" smd roundrect (at -0.485 0 90) (size 0.59 0.64) (layers "B.Cu" "B.Paste" "B.Mask") (roundrect_rratio 0.25)
      (net 15 "PS_3V3") (pintype "passive"))
    (pad "2" smd roundrect (at 0.485 0 90) (size 0.59 0.64) (layers "B.Cu" "B.Paste" "B.Mask") (roundrect_rratio 0.25)
      (net 275 "/USB/VBUS") (pintype "passive"))
  )
	(footprint "kria-k26-devboard-footprints:R_0402_1005Metric" (layer "B.Cu")
    (at 122.2 146.55 -90)
    (descr "Resistor SMD 0402")
    (tags "resistor SMD 0402")
    (property "Author" "Antmicro")
    (property "License" "Apache-2.0")
    (property "MPN" "CR0402-FX-1001GLF")
    (property "Manufacturer" "Bourns")
    (property "Sheetfile" "sd-3-card.kicad_sch")
    (property "Sheetname" "SD 3.0 card")
    (property "Tolerance" "1%")
    (property "Val" "1k")
    (property "ki_description" "1k resistor in 0402 package with 1% tolerance")
    (attr smd)
    (fp_text reference "R17" (at 0.87 -0.41 90) (layer "B.SilkS")
        (effects (font (size 0.7 0.7) (thickness 0.15)) (justify left bottom mirror))
    )
    (fp_text value "R_1k_0402" (at 0 -1.4 90) (layer "B.Fab") hide
        (effects (font (size 0.7 0.7) (thickness 0.15)) (justify left bottom mirror))
    )
    (fp_text user "${REFERENCE}" (at -0.95 -3.168 90) (layer "B.Fab") hide
        (effects (font (size 0.7 0.7) (thickness 0.15)) (justify left bottom mirror))
    )
    (fp_text user "License: Apache-2.0" (at -0.95 -5.169 90) (layer "B.Fab") hide
        (effects (font (size 0.7 0.7) (thickness 0.15)) (justify left bottom mirror))
    )
    (fp_text user "Author: Antmicro" (at -0.95 -4.169 90) (layer "B.Fab") hide
        (effects (font (size 0.7 0.7) (thickness 0.15)) (justify left bottom mirror))
    )
    (fp_rect (start -0.93 0.47) (end 0.93 -0.47)
      (stroke (width 0.05) (type solid)) (fill none) (layer "B.CrtYd"))
    (fp_rect (start -0.5 0.25) (end 0.5 -0.25)
      (stroke (width 0.15) (type solid)) (fill none) (layer "B.Fab"))
    (pad "1" smd roundrect (at -0.485 0 270) (size 0.59 0.64) (layers "B.Cu" "B.Paste" "B.Mask") (roundrect_rratio 0.25)
      (net 415 "Net-(Q1-D)") (pintype "passive"))
    (pad "2" smd roundrect (at 0.485 0 270) (size 0.59 0.64) (layers "B.Cu" "B.Paste" "B.Mask") (roundrect_rratio 0.25)
      (net 131 "Net-(Q2-G)") (pintype "passive"))
  )
	(footprint "kria-k26-devboard-footprints:C_0603_1608Metric" (layer "B.Cu")
    (at 130.45 146.1)
    (descr "Capacitor SMD 0603")
    (tags "capacitor 0603")
    (property "Author" "Antmicro")
    (property "License" "Apache-2.0")
    (property "MPN" "GRM188R61A106KE69D")
    (property "Manufacturer" "Murata")
    (property "Sheetfile" "sd-3-card.kicad_sch")
    (property "Sheetname" "SD 3.0 card")
    (property "Val" "10u")
    (property "Voltage" "")
    (property "ki_description" " ")
    (attr smd)
    (fp_text reference "C20" (at 3.34 0.36 180) (layer "B.SilkS")
        (effects (font (size 0.7 0.7) (thickness 0.15)) (justify left bottom mirror))
    )
    (fp_text value "C_10u_0603" (at 0 -1.6 180) (layer "B.Fab") hide
        (effects (font (size 0.7 0.7) (thickness 0.15)) (justify left bottom mirror))
    )
    (fp_text user "Author: Antmicro" (at -1.682 -4.894 180) (layer "B.Fab") hide
        (effects (font (size 0.7 0.7) (thickness 0.15)) (justify left bottom mirror))
    )
    (fp_text user "${REFERENCE}" (at -1.682 -3.895 180) (layer "B.Fab") hide
        (effects (font (size 0.7 0.7) (thickness 0.15)) (justify left bottom mirror))
    )
    (fp_text user "License: Apache-2.0" (at -1.682 -5.895 180) (layer "B.Fab") hide
        (effects (font (size 0.7 0.7) (thickness 0.15)) (justify left bottom mirror))
    )
    (fp_line (start -0.3 -0.3) (end 0.3 -0.3)
      (stroke (width 0.15) (type solid)) (layer "B.SilkS"))
    (fp_line (start -0.3 0.3) (end 0.3 0.3)
      (stroke (width 0.15) (type solid)) (layer "B.SilkS"))
    (fp_rect (start -1.24 0.7) (end 1.24 -0.7)
      (stroke (width 0.05) (type solid)) (fill none) (layer "B.CrtYd"))
    (fp_rect (start -0.8 0.4) (end 0.8 -0.4)
      (stroke (width 0.15) (type solid)) (fill none) (layer "B.Fab"))
    (pad "1" smd roundrect (at -0.7 0) (size 0.6 0.8) (layers "B.Cu" "B.Paste" "B.Mask") (roundrect_rratio 0.2)
      (net 317 "/SD 3.0 card/SD_VDD") (pintype "passive"))
    (pad "2" smd roundrect (at 0.7 0) (size 0.6 0.8) (layers "B.Cu" "B.Paste" "B.Mask") (roundrect_rratio 0.2)
      (net 1 "GND") (pintype "passive"))
  )
	(footprint "kria-k26-devboard-footprints:C_0402_1005Metric" (layer "B.Cu")
    (at 130.25 147.29)
    (descr "Capacitor SMD 0402")
    (tags "capacitor SMD 0402")
    (property "Author" "Antmicro")
    (property "Dielectric" "X5R")
    (property "License" "Apache-2.0")
    (property "MPN" "GRM155R61H104KE14D")
    (property "Manufacturer" "Murata")
    (property "Sheetfile" "sd-3-card.kicad_sch")
    (property "Sheetname" "SD 3.0 card")
    (property "Val" "100n")
    (property "Voltage" "50V")
    (property "ki_description" " ")
    (attr smd)
    (fp_text reference "C19" (at 3.1 0.53 180) (layer "B.SilkS")
        (effects (font (size 0.7 0.7) (thickness 0.15)) (justify left bottom mirror))
    )
    (fp_text value "C_100n_0402" (at 0 -1.4 180) (layer "B.Fab") hide
        (effects (font (size 0.7 0.7) (thickness 0.15)) (justify left bottom mirror))
    )
    (fp_text user "${REFERENCE}" (at -0.932 -3.168 180) (layer "B.Fab") hide
        (effects (font (size 0.7 0.7) (thickness 0.15)) (justify left bottom mirror))
    )
    (fp_text user "Author: Antmicro" (at -0.932 -4.17 180) (layer "B.Fab") hide
        (effects (font (size 0.7 0.7) (thickness 0.15)) (justify left bottom mirror))
    )
    (fp_text user "License: Apache-2.0" (at -0.932 -5.17 180) (layer "B.Fab") hide
        (effects (font (size 0.7 0.7) (thickness 0.15)) (justify left bottom mirror))
    )
    (fp_rect (start -0.94 0.47) (end 0.94 -0.47)
      (stroke (width 0.05) (type solid)) (fill none) (layer "B.CrtYd"))
    (fp_rect (start -0.499 0.249) (end 0.499 -0.249)
      (stroke (width 0.15) (type solid)) (fill none) (layer "B.Fab"))
    (pad "1" smd roundrect (at -0.484 0) (size 0.59 0.64) (layers "B.Cu" "B.Paste" "B.Mask") (roundrect_rratio 0.25)
      (net 317 "/SD 3.0 card/SD_VDD") (pintype "passive"))
    (pad "2" smd roundrect (at 0.484 0) (size 0.59 0.64) (layers "B.Cu" "B.Paste" "B.Mask") (roundrect_rratio 0.25)
      (net 1 "GND") (pintype "passive"))
  )
)
